(kicad_pcb
	(version 20260206)
	(generator "pcbnew")
	(generator_version "10.0")
	(general
		(thickness 1.6)
		(legacy_teardrops no)
	)
	(paper "A4")
	(title_block
		(title "01162023_DA0F0TEBIF0_F0T_Expander_BD_F_brd_V02_OCP.brd")
		(comment 1 "Grand Teton / footprints 5358-5363 of 9728")
	)
	(layers
		(0 "F.Cu" signal "TOP")
		(4 "In1.Cu" signal "GND")
		(6 "In2.Cu" signal "VCC")
		(8 "In3.Cu" signal "VCC1")
		(10 "In4.Cu" signal "GND1")
		(12 "In5.Cu" signal "IN1")
		(14 "In6.Cu" signal "GND2")
		(16 "In7.Cu" signal "IN2")
		(18 "In8.Cu" signal "GND3")
		(20 "In9.Cu" signal "IN3")
		(22 "In10.Cu" signal "GND4")
		(24 "In11.Cu" signal "IN4")
		(26 "In12.Cu" signal "GND5")
		(28 "In13.Cu" signal "IN5")
		(30 "In14.Cu" signal "GND6")
		(32 "In15.Cu" signal "IN6")
		(34 "In16.Cu" signal "GND7")
		(2 "B.Cu" signal "BOTTOM")
		(9 "F.Adhes" user "F.Adhesive")
		(11 "B.Adhes" user "B.Adhesive")
		(13 "F.Paste" user "Package Geometry/Pastemask Top")
		(15 "B.Paste" user "Package Geometry/Pastemask Bottom")
		(5 "F.SilkS" user "Ref Des/Silkscreen Top")
		(7 "B.SilkS" user "Ref Des/Silkscreen Bottom")
		(1 "F.Mask" user "Board Geometry/Soldermask Top")
		(3 "B.Mask" user "Board Geometry/Soldermask Bottom")
		(17 "Dwgs.User" user "User.Drawings")
		(19 "Cmts.User" user "User.Comments")
		(21 "Eco1.User" user "User.Eco1")
		(23 "Eco2.User" user "User.Eco2")
		(25 "Edge.Cuts" user "Board Geometry/Outline")
		(27 "Margin" user)
		(31 "F.CrtYd" user "Package Geometry/Place Bound Top")
		(29 "B.CrtYd" user "Package Geometry/Place Bound Bottom")
		(35 "F.Fab" user "Ref Des/Assembly Top")
		(33 "B.Fab" user "Ref Des/Assembly Bottom")
	)
	(footprint ""
		(layer "F.Cu")
		(at 149.171406 -243.130578 180)
		(property "Reference" "R6576"
			(at 0 0 180)
			(layer "F.SilkS")
			(hide yes)
			(effects
				(font
					(size 1.27 1.27)
				)
			)
		)
		(property "Value" ""
			(at 0 0 180)
			(layer "F.Fab")
			(effects
				(font
					(size 1.27 1.27)
				)
			)
		)
		(duplicate_pad_numbers_are_jumpers no)
		(fp_line
			(start 0.7874 0.4064)
			(end -0.7874 0.4064)
			(stroke
				(width 0.1524)
				(type default)
			)
			(layer "F.SilkS")
		)
		(fp_line
			(start 0.7874 -0.4064)
			(end 0.7874 0.4064)
			(stroke
				(width 0.1524)
				(type default)
			)
			(layer "F.SilkS")
		)
		(fp_line
			(start -0.7874 0.4064)
			(end -0.7874 -0.4064)
			(stroke
				(width 0.1524)
				(type default)
			)
			(layer "F.SilkS")
		)
		(fp_line
			(start -0.7874 -0.4064)
			(end 0.7874 -0.4064)
			(stroke
				(width 0.1524)
				(type default)
			)
			(layer "F.SilkS")
		)
		(fp_line
			(start 0.67945 0.3048)
			(end 0.120396 0.3048)
			(stroke
				(width 0.1)
				(type default)
			)
			(layer "F.Fab")
		)
		(fp_line
			(start 0.67945 -0.3048)
			(end 0.67945 0.3048)
			(stroke
				(width 0.1)
				(type default)
			)
			(layer "F.Fab")
		)
		(fp_line
			(start 0.12065 -0.2794)
			(end 0.12065 -0.3048)
			(stroke
				(width 0.1)
				(type default)
			)
			(layer "F.Fab")
		)
		(fp_line
			(start 0.12065 -0.3048)
			(end 0.67945 -0.3048)
			(stroke
				(width 0.1)
				(type default)
			)
			(layer "F.Fab")
		)
		(fp_line
			(start 0.120396 0.3048)
			(end 0.120396 0.2794)
			(stroke
				(width 0.1)
				(type default)
			)
			(layer "F.Fab")
		)
		(fp_line
			(start 0.120396 0.2794)
			(end -0.12065 0.2794)
			(stroke
				(width 0.1)
				(type default)
			)
			(layer "F.Fab")
		)
		(fp_line
			(start -0.12065 0.3048)
			(end -0.67945 0.3048)
			(stroke
				(width 0.1)
				(type default)
			)
			(layer "F.Fab")
		)
		(fp_line
			(start -0.12065 0.2794)
			(end -0.12065 0.3048)
			(stroke
				(width 0.1)
				(type default)
			)
			(layer "F.Fab")
		)
		(fp_line
			(start -0.12065 -0.2794)
			(end 0.12065 -0.2794)
			(stroke
				(width 0.1)
				(type default)
			)
			(layer "F.Fab")
		)
		(fp_line
			(start -0.12065 -0.305054)
			(end -0.12065 -0.2794)
			(stroke
				(width 0.1)
				(type default)
			)
			(layer "F.Fab")
		)
		(fp_line
			(start -0.67945 0.3048)
			(end -0.67945 -0.305054)
			(stroke
				(width 0.1)
				(type default)
			)
			(layer "F.Fab")
		)
		(fp_line
			(start -0.67945 -0.305054)
			(end -0.12065 -0.305054)
			(stroke
				(width 0.1)
				(type default)
			)
			(layer "F.Fab")
		)
		(pad "1" smd circle
			(at -0.40005 0 180)
			(size 0 0)
			(layers "F.Cu" "F.Mask" "F.Paste")
			(net "PWRGD_PEX1_P1V8_PLL_R")
		)
		(pad "2" smd circle
			(at 0.40005 0 180)
			(size 0 0)
			(layers "F.Cu" "F.Mask" "F.Paste")
			(net "PWRGD_PEX1_P1V8_PLL")
		)
	)
	(footprint ""
		(layer "F.Cu")
		(at 174.991014 -55.663846 90)
		(property "Reference" "PU58"
			(at -1.524 2.792222 90)
			(unlocked yes)
			(layer "F.SilkS")
			(effects
				(font
					(size 0.7874 0.5842)
					(thickness 0.1524)
				)
				(justify left)
			)
		)
		(property "Value" ""
			(at 0 0 90)
			(layer "F.Fab")
			(effects
				(font
					(size 1.27 1.27)
				)
			)
		)
		(duplicate_pad_numbers_are_jumpers no)
		(fp_line
			(start 1.943608 -1.549908)
			(end 1.943608 1.549908)
			(stroke
				(width 0.1524)
				(type default)
			)
			(layer "F.SilkS")
		)
		(fp_line
			(start -1.943608 -1.549908)
			(end 1.943608 -1.549908)
			(stroke
				(width 0.1524)
				(type default)
			)
			(layer "F.SilkS")
		)
		(fp_line
			(start 1.943608 1.549908)
			(end -1.943608 1.549908)
			(stroke
				(width 0.1524)
				(type default)
			)
			(layer "F.SilkS")
		)
		(fp_line
			(start -1.943608 1.549908)
			(end -1.943608 -1.549908)
			(stroke
				(width 0.1524)
				(type default)
			)
			(layer "F.SilkS")
		)
		(fp_poly
			(pts
				(xy -2.019808 -1.549908) (xy -1.257808 -1.549908) (xy -1.257808 -1.880108) (xy -2.019808 -1.880108)
			)
			(stroke
				(width 0)
				(type default)
			)
			(fill yes)
			(layer "F.SilkS")
		)
		(fp_line
			(start 1.549908 -1.549908)
			(end 1.549908 1.549908)
			(stroke
				(width 0.1)
				(type default)
			)
			(layer "F.Fab")
		)
		(fp_line
			(start -1.549908 -1.549908)
			(end 1.549908 -1.549908)
			(stroke
				(width 0.1)
				(type default)
			)
			(layer "F.Fab")
		)
		(fp_line
			(start 1.549908 1.549908)
			(end -1.549908 1.549908)
			(stroke
				(width 0.1)
				(type default)
			)
			(layer "F.Fab")
		)
		(fp_line
			(start -1.549908 1.549908)
			(end -1.549908 -1.549908)
			(stroke
				(width 0.1)
				(type default)
			)
			(layer "F.Fab")
		)
		(fp_poly
			(pts
				(xy -2.019808 -1.549908) (xy -1.257808 -1.549908) (xy -1.257808 -1.880108) (xy -2.019808 -1.880108)
			)
			(stroke
				(width 0)
				(type default)
			)
			(fill yes)
			(layer "F.Fab")
		)
		(pad "1" smd rect
			(at -1.500124 -1.249934)
			(size 0.2794 0.6096)
			(layers "F.Cu" "F.Mask" "F.Paste")
			(net "P3V3_SSD6")
		)
		(pad "2" smd rect
			(at -1.500124 -0.750062)
			(size 0.2794 0.6096)
			(layers "F.Cu" "F.Mask" "F.Paste")
			(net "P3V3_SSD6")
		)
		(pad "3" smd rect
			(at -1.500124 -0.249936)
			(size 0.2794 0.6096)
			(layers "F.Cu" "F.Mask" "F.Paste")
			(net "P3V3_SSD6")
		)
		(pad "4" smd rect
			(at -1.500124 0.249936)
			(size 0.2794 0.6096)
			(layers "F.Cu" "F.Mask" "F.Paste")
			(net "P3V3_SSD6")
		)
		(pad "5" smd rect
			(at -1.500124 0.750062)
			(size 0.2794 0.6096)
			(layers "F.Cu" "F.Mask" "F.Paste")
			(net "P3V3_SSD6")
		)
		(pad "6" smd rect
			(at -1.500124 1.249934)
			(size 0.2794 0.6096)
			(layers "F.Cu" "F.Mask" "F.Paste")
			(net "GND")
		)
		(pad "7" smd rect
			(at 1.500124 1.249934)
			(size 0.2794 0.6096)
			(layers "F.Cu" "F.Mask" "F.Paste")
			(net "P3V3_SSD6_SS")
		)
		(pad "8" smd rect
			(at 1.500124 0.750062)
			(size 0.2794 0.6096)
			(layers "F.Cu" "F.Mask" "F.Paste")
			(net "PWRGD_P3V3_SSD6")
		)
		(pad "9" smd rect
			(at 1.500124 0.249936)
			(size 0.2794 0.6096)
			(layers "F.Cu" "F.Mask" "F.Paste")
			(net "P3V3_SSD6_OCP")
		)
		(pad "10" smd rect
			(at 1.500124 -0.249936)
			(size 0.2794 0.6096)
			(layers "F.Cu" "F.Mask" "F.Paste")
			(net "P5V_AUX")
		)
		(pad "11" smd rect
			(at 1.500124 -0.750062)
			(size 0.2794 0.6096)
			(layers "F.Cu" "F.Mask" "F.Paste")
			(net "SSD6_AUX_P3V3_EN_R")
		)
		(pad "12" smd rect
			(at 1.500124 -1.249934)
			(size 0.2794 0.6096)
			(layers "F.Cu" "F.Mask" "F.Paste")
			(net "P3V3_AUX")
		)
		(pad "13" smd rect
			(at 0 0 90)
			(size 1.9812 2.7178)
			(layers "F.Cu" "F.Mask" "F.Paste")
			(net "P3V3_AUX")
		)
		(zone
			(layer "F.Cu")
			(hatch none 0.5)
			(connect_pads
				(clearance 0)
			)
			(min_thickness 0.25)
			(keepout
				(tracks not_allowed)
				(vias allowed)
				(pads allowed)
				(copperpour not_allowed)
				(footprints allowed)
			)
			(placement
				(enabled no)
				(sheetname "")
			)
			(fill
				(thermal_gap 0.5)
				(thermal_bridge_width 0.5)
				(island_removal_mode 0)
			)
			(polygon
				(pts
					(xy 173.441614 -56.806846) (xy 173.568614 -56.806846) (xy 176.540414 -56.806846) (xy 176.540922 -56.806846)
					(xy 176.540922 -54.520846) (xy 176.540414 -54.520846) (xy 176.413414 -54.520846) (xy 174.991014 -54.520846)
					(xy 174.991014 -54.622446) (xy 176.413414 -54.622446) (xy 176.413414 -56.705246) (xy 173.568614 -56.705246)
					(xy 173.568614 -54.622446) (xy 174.965614 -54.622446) (xy 174.965614 -54.520846) (xy 173.568614 -54.520846)
					(xy 173.441614 -54.520846) (xy 173.441106 -54.520846) (xy 173.441106 -56.806846)
				)
			)
		)
	)
	(footprint ""
		(layer "F.Cu")
		(at 374.543828 -43.85691)
		(property "Reference" "R640"
			(at 0 0 0)
			(layer "F.SilkS")
			(hide yes)
			(effects
				(font
					(size 1.27 1.27)
				)
			)
		)
		(property "Value" ""
			(at 0 0 0)
			(layer "F.Fab")
			(effects
				(font
					(size 1.27 1.27)
				)
			)
		)
		(duplicate_pad_numbers_are_jumpers no)
		(fp_line
			(start -0.7874 -0.4064)
			(end 0.7874 -0.4064)
			(stroke
				(width 0.1524)
				(type default)
			)
			(layer "F.SilkS")
		)
		(fp_line
			(start -0.7874 0.4064)
			(end -0.7874 -0.4064)
			(stroke
				(width 0.1524)
				(type default)
			)
			(layer "F.SilkS")
		)
		(fp_line
			(start 0.7874 -0.4064)
			(end 0.7874 0.4064)
			(stroke
				(width 0.1524)
				(type default)
			)
			(layer "F.SilkS")
		)
		(fp_line
			(start 0.7874 0.4064)
			(end -0.7874 0.4064)
			(stroke
				(width 0.1524)
				(type default)
			)
			(layer "F.SilkS")
		)
		(fp_line
			(start -0.67945 -0.305054)
			(end -0.12065 -0.305054)
			(stroke
				(width 0.1)
				(type default)
			)
			(layer "F.Fab")
		)
		(fp_line
			(start -0.67945 0.3048)
			(end -0.67945 -0.305054)
			(stroke
				(width 0.1)
				(type default)
			)
			(layer "F.Fab")
		)
		(fp_line
			(start -0.12065 -0.305054)
			(end -0.12065 -0.2794)
			(stroke
				(width 0.1)
				(type default)
			)
			(layer "F.Fab")
		)
		(fp_line
			(start -0.12065 -0.2794)
			(end 0.12065 -0.2794)
			(stroke
				(width 0.1)
				(type default)
			)
			(layer "F.Fab")
		)
		(fp_line
			(start -0.12065 0.2794)
			(end -0.12065 0.3048)
			(stroke
				(width 0.1)
				(type default)
			)
			(layer "F.Fab")
		)
		(fp_line
			(start -0.12065 0.3048)
			(end -0.67945 0.3048)
			(stroke
				(width 0.1)
				(type default)
			)
			(layer "F.Fab")
		)
		(fp_line
			(start 0.120396 0.2794)
			(end -0.12065 0.2794)
			(stroke
				(width 0.1)
				(type default)
			)
			(layer "F.Fab")
		)
		(fp_line
			(start 0.120396 0.3048)
			(end 0.120396 0.2794)
			(stroke
				(width 0.1)
				(type default)
			)
			(layer "F.Fab")
		)
		(fp_line
			(start 0.12065 -0.3048)
			(end 0.67945 -0.3048)
			(stroke
				(width 0.1)
				(type default)
			)
			(layer "F.Fab")
		)
		(fp_line
			(start 0.12065 -0.2794)
			(end 0.12065 -0.3048)
			(stroke
				(width 0.1)
				(type default)
			)
			(layer "F.Fab")
		)
		(fp_line
			(start 0.67945 -0.3048)
			(end 0.67945 0.3048)
			(stroke
				(width 0.1)
				(type default)
			)
			(layer "F.Fab")
		)
		(fp_line
			(start 0.67945 0.3048)
			(end 0.120396 0.3048)
			(stroke
				(width 0.1)
				(type default)
			)
			(layer "F.Fab")
		)
		(pad "1" smd circle
			(at -0.40005 0)
			(size 0 0)
			(layers "F.Cu" "F.Mask" "F.Paste")
			(net "SSD12_ADC_A1")
		)
		(pad "2" smd circle
			(at 0.40005 0)
			(size 0 0)
			(layers "F.Cu" "F.Mask" "F.Paste")
			(net "GND")
		)
	)
	(footprint ""
		(layer "F.Cu")
		(at 147.750276 -50.96383 180)
		(property "Reference" "PC515"
			(at 0 0 180)
			(layer "F.SilkS")
			(hide yes)
			(effects
				(font
					(size 1.27 1.27)
				)
			)
		)
		(property "Value" ""
			(at 0 0 180)
			(layer "F.Fab")
			(effects
				(font
					(size 1.27 1.27)
				)
			)
		)
		(duplicate_pad_numbers_are_jumpers no)
		(fp_line
			(start 1.524 0.762)
			(end -1.524 0.762)
			(stroke
				(width 0.1524)
				(type default)
			)
			(layer "F.SilkS")
		)
		(fp_line
			(start 1.524 -0.762)
			(end 1.524 0.762)
			(stroke
				(width 0.1524)
				(type default)
			)
			(layer "F.SilkS")
		)
		(fp_line
			(start -1.524 0.762)
			(end -1.524 -0.762)
			(stroke
				(width 0.1524)
				(type default)
			)
			(layer "F.SilkS")
		)
		(fp_line
			(start -1.524 -0.762)
			(end 1.524 -0.762)
			(stroke
				(width 0.1524)
				(type default)
			)
			(layer "F.SilkS")
		)
		(fp_line
			(start 1.1049 0.724916)
			(end 1.1049 -0.724916)
			(stroke
				(width 0.1)
				(type default)
			)
			(layer "F.Fab")
		)
		(fp_line
			(start 1.1049 -0.724916)
			(end -1.1049 -0.724916)
			(stroke
				(width 0.1)
				(type default)
			)
			(layer "F.Fab")
		)
		(fp_line
			(start -1.1049 0.724916)
			(end 1.1049 0.724916)
			(stroke
				(width 0.1)
				(type default)
			)
			(layer "F.Fab")
		)
		(fp_line
			(start -1.1049 -0.724916)
			(end -1.1049 0.724916)
			(stroke
				(width 0.1)
				(type default)
			)
			(layer "F.Fab")
		)
		(pad "1" smd rect
			(at -0.889 0)
			(size 1.016 1.27)
			(layers "F.Cu" "F.Mask" "F.Paste")
			(net "P3V3_SSD5")
		)
		(pad "2" smd rect
			(at 0.889 0)
			(size 1.016 1.27)
			(layers "F.Cu" "F.Mask" "F.Paste")
			(net "GND")
		)
	)
	(footprint ""
		(layer "F.Cu")
		(at 135.508238 -142.455392 180)
		(property "Reference" "R704"
			(at 0 0 180)
			(layer "F.SilkS")
			(hide yes)
			(effects
				(font
					(size 1.27 1.27)
				)
			)
		)
		(property "Value" ""
			(at 0 0 180)
			(layer "F.Fab")
			(effects
				(font
					(size 1.27 1.27)
				)
			)
		)
		(duplicate_pad_numbers_are_jumpers no)
		(fp_line
			(start 3.937508 1.8796)
			(end 3.937508 -1.8796)
			(stroke
				(width 0.1524)
				(type default)
			)
			(layer "F.SilkS")
		)
		(fp_line
			(start 3.937508 -1.8796)
			(end -3.937508 -1.8796)
			(stroke
				(width 0.1524)
				(type default)
			)
			(layer "F.SilkS")
		)
		(fp_line
			(start -3.937508 1.8796)
			(end 3.937508 1.8796)
			(stroke
				(width 0.1524)
				(type default)
			)
			(layer "F.SilkS")
		)
		(fp_line
			(start -3.937508 -1.8796)
			(end -3.937508 1.8796)
			(stroke
				(width 0.1524)
				(type default)
			)
			(layer "F.SilkS")
		)
		(fp_line
			(start 3.275076 1.674876)
			(end 3.275076 -1.674876)
			(stroke
				(width 0.1)
				(type default)
			)
			(layer "F.Fab")
		)
		(fp_line
			(start 3.275076 -1.674876)
			(end -3.275076 -1.674876)
			(stroke
				(width 0.1)
				(type default)
			)
			(layer "F.Fab")
		)
		(fp_line
			(start -3.275076 1.674876)
			(end 3.275076 1.674876)
			(stroke
				(width 0.1)
				(type default)
			)
			(layer "F.Fab")
		)
		(fp_line
			(start -3.275076 -1.674876)
			(end -3.275076 1.674876)
			(stroke
				(width 0.1)
				(type default)
			)
			(layer "F.Fab")
		)
		(pad "1" smd rect
			(at -2.350008 0 180)
			(size 2.921 3.5052)
			(layers "F.Cu" "F.Mask" "F.Paste")
			(net "P12V_NIC2")
		)
		(pad "2" smd rect
			(at 2.350008 0 180)
			(size 2.921 3.5052)
			(layers "F.Cu" "F.Mask" "F.Paste")
			(net "P12V_NIC2_R")
		)
	)
	(footprint ""
		(layer "F.Cu")
		(at 86.110318 -63.652146 180)
		(property "Reference" "R5851"
			(at 0 0 180)
			(layer "F.SilkS")
			(hide yes)
			(effects
				(font
					(size 1.27 1.27)
				)
			)
		)
		(property "Value" ""
			(at 0 0 180)
			(layer "F.Fab")
			(effects
				(font
					(size 1.27 1.27)
				)
			)
		)
		(duplicate_pad_numbers_are_jumpers no)
		(fp_line
			(start 0.7874 0.4064)
			(end -0.7874 0.4064)
			(stroke
				(width 0.1524)
				(type default)
			)
			(layer "F.SilkS")
		)
		(fp_line
			(start 0.7874 -0.4064)
			(end 0.7874 0.4064)
			(stroke
				(width 0.1524)
				(type default)
			)
			(layer "F.SilkS")
		)
		(fp_line
			(start -0.7874 0.4064)
			(end -0.7874 -0.4064)
			(stroke
				(width 0.1524)
				(type default)
			)
			(layer "F.SilkS")
		)
		(fp_line
			(start -0.7874 -0.4064)
			(end 0.7874 -0.4064)
			(stroke
				(width 0.1524)
				(type default)
			)
			(layer "F.SilkS")
		)
		(fp_line
			(start 0.67945 0.3048)
			(end 0.120396 0.3048)
			(stroke
				(width 0.1)
				(type default)
			)
			(layer "F.Fab")
		)
		(fp_line
			(start 0.67945 -0.3048)
			(end 0.67945 0.3048)
			(stroke
				(width 0.1)
				(type default)
			)
			(layer "F.Fab")
		)
		(fp_line
			(start 0.12065 -0.2794)
			(end 0.12065 -0.3048)
			(stroke
				(width 0.1)
				(type default)
			)
			(layer "F.Fab")
		)
		(fp_line
			(start 0.12065 -0.3048)
			(end 0.67945 -0.3048)
			(stroke
				(width 0.1)
				(type default)
			)
			(layer "F.Fab")
		)
		(fp_line
			(start 0.120396 0.3048)
			(end 0.120396 0.2794)
			(stroke
				(width 0.1)
				(type default)
			)
			(layer "F.Fab")
		)
		(fp_line
			(start 0.120396 0.2794)
			(end -0.12065 0.2794)
			(stroke
				(width 0.1)
				(type default)
			)
			(layer "F.Fab")
		)
		(fp_line
			(start -0.12065 0.3048)
			(end -0.67945 0.3048)
			(stroke
				(width 0.1)
				(type default)
			)
			(layer "F.Fab")
		)
		(fp_line
			(start -0.12065 0.2794)
			(end -0.12065 0.3048)
			(stroke
				(width 0.1)
				(type default)
			)
			(layer "F.Fab")
		)
		(fp_line
			(start -0.12065 -0.2794)
			(end 0.12065 -0.2794)
			(stroke
				(width 0.1)
				(type default)
			)
			(layer "F.Fab")
		)
		(fp_line
			(start -0.12065 -0.305054)
			(end -0.12065 -0.2794)
			(stroke
				(width 0.1)
				(type default)
			)
			(layer "F.Fab")
		)
		(fp_line
			(start -0.67945 0.3048)
			(end -0.67945 -0.305054)
			(stroke
				(width 0.1)
				(type default)
			)
			(layer "F.Fab")
		)
		(fp_line
			(start -0.67945 -0.305054)
			(end -0.12065 -0.305054)
			(stroke
				(width 0.1)
				(type default)
			)
			(layer "F.Fab")
		)
		(pad "1" smd circle
			(at -0.40005 0 180)
			(size 0 0)
			(layers "F.Cu" "F.Mask" "F.Paste")
			(net "P5V_AUX")
		)
		(pad "2" smd circle
			(at 0.40005 0 180)
			(size 0 0)
			(layers "F.Cu" "F.Mask" "F.Paste")
			(net "P12V_SSD3_PG_G2")
		)
	)
)
